# BARRELEYE_G2-BPX24-EVT-HW-EBOM-X00_20161124-add_2nd_source_X09-20161207-Final.xls — TLA (bom)
| FOXCONN TECHNOLOGY GROUP |  |  |  |  |  |  |  |  |  |
| BILL OF MATERIAL |  |  |  |  |  |  |  |  |  |
| AA P/N | 1A42GBW00-600-G | CUSTOMER | <name> | Customer P/N |  | Product Code |  |  |  |
| PWA P/N |  | PWA DESCRIPTION | 24顆硬盤背板,ASSY,24xHDD BACKPLANE,G,BARRELEYE G2 |  |  | PWA REV | X00 | Prepared By SE |  |
| Item | FOXCONN P/N | Customer P/N | Part Description | Manufacturer  Full Name | Manufacturer  Part Number | Qty | RoHS Status | Location | Remark |
| 1 | 7J-004-938 |  | L6 LABEL ( 12.7*11.1mm) | FOXCONN / EPD1 | 7J-004-938 | 1 | G |  |  |
| 2 | 1B51GF500-600-G |  | 8_MYLAR-HDD-BP-FRONT_POWER9 | FOXCONN / EPD5 | 1B51GF500-600-G | 1 | G |  | Rev.X01 |
